(kicad_pcb
	(version 20260206)
	(generator "pcbnew")
	(generator_version "10.0")
	(general
		(thickness 1.6)
		(legacy_teardrops no)
	)
	(paper "A4")
	(title_block
		(title "03242023_DA0F0TMBIJ0_F0T_Motherboard_J_brd_V01_OCP.brd")
		(comment 1 "Grand Teton / footprints 1252-1253 of 6105")
	)
	(layers
		(0 "F.Cu" signal "TOP")
		(4 "In1.Cu" signal "GND")
		(6 "In2.Cu" signal "IN1")
		(8 "In3.Cu" signal "GND1")
		(10 "In4.Cu" signal "IN2")
		(12 "In5.Cu" signal "GND2")
		(14 "In6.Cu" signal "IN3")
		(16 "In7.Cu" signal "GND3")
		(18 "In8.Cu" signal "VCC")
		(20 "In9.Cu" signal "VCC1")
		(22 "In10.Cu" signal "GND4")
		(24 "In11.Cu" signal "IN4")
		(26 "In12.Cu" signal "GND5")
		(28 "In13.Cu" signal "IN5")
		(30 "In14.Cu" signal "GND6")
		(32 "In15.Cu" signal "IN6")
		(34 "In16.Cu" signal "GND7")
		(2 "B.Cu" signal "BOTTOM")
		(9 "F.Adhes" user "F.Adhesive")
		(11 "B.Adhes" user "B.Adhesive")
		(13 "F.Paste" user "Package Geometry/Pastemask Top")
		(15 "B.Paste" user "Package Geometry/Pastemask Bottom")
		(5 "F.SilkS" user "Ref Des/Silkscreen Top")
		(7 "B.SilkS" user "Ref Des/Silkscreen Bottom")
		(1 "F.Mask" user "Board Geometry/Soldermask Top")
		(3 "B.Mask" user "Board Geometry/Soldermask Bottom")
		(17 "Dwgs.User" user "User.Drawings")
		(19 "Cmts.User" user "User.Comments")
		(21 "Eco1.User" user "User.Eco1")
		(23 "Eco2.User" user "User.Eco2")
		(25 "Edge.Cuts" user "Board Geometry/Outline")
		(27 "Margin" user)
		(31 "F.CrtYd" user "Package Geometry/Place Bound Top")
		(29 "B.CrtYd" user "Package Geometry/Place Bound Bottom")
		(35 "F.Fab" user "Ref Des/Assembly Top")
		(33 "B.Fab" user "Ref Des/Assembly Bottom")
	)
	(footprint ""
		(layer "F.Cu")
		(at 29.51988 -430.875948)
		(property "Reference" "C1977"
			(at 0 0 0)
			(layer "F.SilkS")
			(hide yes)
			(effects
				(font
					(size 1.27 1.27)
				)
			)
		)
		(property "Value" ""
			(at 0 0 0)
			(layer "F.Fab")
			(effects
				(font
					(size 1.27 1.27)
				)
			)
		)
		(duplicate_pad_numbers_are_jumpers no)
		(fp_line
			(start -0.7874 -0.4064)
			(end 0.7874 -0.4064)
			(stroke
				(width 0.1524)
				(type default)
			)
			(layer "F.SilkS")
		)
		(fp_line
			(start -0.7874 0.4064)
			(end -0.7874 -0.4064)
			(stroke
				(width 0.1524)
				(type default)
			)
			(layer "F.SilkS")
		)
		(fp_line
			(start 0.7874 -0.4064)
			(end 0.7874 0.4064)
			(stroke
				(width 0.1524)
				(type default)
			)
			(layer "F.SilkS")
		)
		(fp_line
			(start 0.7874 0.4064)
			(end -0.7874 0.4064)
			(stroke
				(width 0.1524)
				(type default)
			)
			(layer "F.SilkS")
		)
		(fp_line
			(start -0.67945 -0.305054)
			(end -0.12065 -0.305054)
			(stroke
				(width 0.1)
				(type default)
			)
			(layer "F.Fab")
		)
		(fp_line
			(start -0.67945 0.3048)
			(end -0.67945 -0.305054)
			(stroke
				(width 0.1)
				(type default)
			)
			(layer "F.Fab")
		)
		(fp_line
			(start -0.12065 -0.305054)
			(end -0.12065 -0.2794)
			(stroke
				(width 0.1)
				(type default)
			)
			(layer "F.Fab")
		)
		(fp_line
			(start -0.12065 -0.2794)
			(end 0.12065 -0.2794)
			(stroke
				(width 0.1)
				(type default)
			)
			(layer "F.Fab")
		)
		(fp_line
			(start -0.12065 0.2794)
			(end -0.12065 0.3048)
			(stroke
				(width 0.1)
				(type default)
			)
			(layer "F.Fab")
		)
		(fp_line
			(start -0.12065 0.3048)
			(end -0.67945 0.3048)
			(stroke
				(width 0.1)
				(type default)
			)
			(layer "F.Fab")
		)
		(fp_line
			(start 0.120396 0.2794)
			(end -0.12065 0.2794)
			(stroke
				(width 0.1)
				(type default)
			)
			(layer "F.Fab")
		)
		(fp_line
			(start 0.120396 0.3048)
			(end 0.120396 0.2794)
			(stroke
				(width 0.1)
				(type default)
			)
			(layer "F.Fab")
		)
		(fp_line
			(start 0.12065 -0.3048)
			(end 0.67945 -0.3048)
			(stroke
				(width 0.1)
				(type default)
			)
			(layer "F.Fab")
		)
		(fp_line
			(start 0.12065 -0.2794)
			(end 0.12065 -0.3048)
			(stroke
				(width 0.1)
				(type default)
			)
			(layer "F.Fab")
		)
		(fp_line
			(start 0.67945 -0.3048)
			(end 0.67945 0.3048)
			(stroke
				(width 0.1)
				(type default)
			)
			(layer "F.Fab")
		)
		(fp_line
			(start 0.67945 0.3048)
			(end 0.120396 0.3048)
			(stroke
				(width 0.1)
				(type default)
			)
			(layer "F.Fab")
		)
		(pad "1" smd circle
			(at -0.40005 0)
			(size 0 0)
			(layers "F.Cu" "F.Mask" "F.Paste")
			(net "P3V3_AUX")
		)
		(pad "2" smd circle
			(at 0.40005 0)
			(size 0 0)
			(layers "F.Cu" "F.Mask" "F.Paste")
			(net "GND")
		)
	)
	(footprint ""
		(layer "F.Cu")
		(at 425.705016 -136.41451 90)
		(property "Reference" "PU5"
			(at -5.203952 -1.067816 0)
			(unlocked yes)
			(layer "F.SilkS")
			(effects
				(font
					(size 0.7874 0.5842)
					(thickness 0.1524)
				)
				(justify left)
			)
		)
		(property "Value" ""
			(at 0 0 90)
			(layer "F.Fab")
			(effects
				(font
					(size 1.27 1.27)
				)
			)
		)
		(duplicate_pad_numbers_are_jumpers no)
		(fp_line
			(start 0.1778 -3.2385)
			(end 0.1778 -2.8575)
			(stroke
				(width 0.1524)
				(type default)
			)
			(layer "F.SilkS")
		)
		(fp_line
			(start -1.8034 -2.8702)
			(end -1.8034 -3.6322)
			(stroke
				(width 0.1524)
				(type default)
			)
			(layer "F.SilkS")
		)
		(fp_line
			(start 2.500122 -2.500122)
			(end 2.500122 -2.015998)
			(stroke
				(width 0.1524)
				(type default)
			)
			(layer "F.SilkS")
		)
		(fp_line
			(start 2.015998 -2.500122)
			(end 2.500122 -2.500122)
			(stroke
				(width 0.1524)
				(type default)
			)
			(layer "F.SilkS")
		)
		(fp_line
			(start -2.500122 -2.500122)
			(end -2.015998 -2.500122)
			(stroke
				(width 0.1524)
				(type default)
			)
			(layer "F.SilkS")
		)
		(fp_line
			(start -2.500122 -2.015998)
			(end -2.500122 -2.500122)
			(stroke
				(width 0.1524)
				(type default)
			)
			(layer "F.SilkS")
		)
		(fp_line
			(start 2.8702 -1.778)
			(end 3.6322 -1.778)
			(stroke
				(width 0.1524)
				(type default)
			)
			(layer "F.SilkS")
		)
		(fp_line
			(start -3.2639 -0.1778)
			(end -2.8829 -0.1778)
			(stroke
				(width 0.1524)
				(type default)
			)
			(layer "F.SilkS")
		)
		(fp_line
			(start 2.8829 0.2032)
			(end 3.2639 0.2032)
			(stroke
				(width 0.1524)
				(type default)
			)
			(layer "F.SilkS")
		)
		(fp_line
			(start -3.6576 1.8034)
			(end -2.8956 1.8034)
			(stroke
				(width 0.1524)
				(type default)
			)
			(layer "F.SilkS")
		)
		(fp_line
			(start 2.500122 2.015998)
			(end 2.500122 2.500122)
			(stroke
				(width 0.1524)
				(type default)
			)
			(layer "F.SilkS")
		)
		(fp_line
			(start 2.500122 2.500122)
			(end 2.015998 2.500122)
			(stroke
				(width 0.1524)
				(type default)
			)
			(layer "F.SilkS")
		)
		(fp_line
			(start -2.015998 2.500122)
			(end -2.500122 2.500122)
			(stroke
				(width 0.1524)
				(type default)
			)
			(layer "F.SilkS")
		)
		(fp_line
			(start -2.500122 2.500122)
			(end -2.500122 2.018538)
			(stroke
				(width 0.1524)
				(type default)
			)
			(layer "F.SilkS")
		)
		(fp_line
			(start -0.2032 2.8829)
			(end -0.2032 3.2639)
			(stroke
				(width 0.1524)
				(type default)
			)
			(layer "F.SilkS")
		)
		(fp_line
			(start 1.778 3.6322)
			(end 1.778 2.8702)
			(stroke
				(width 0.1524)
				(type default)
			)
			(layer "F.SilkS")
		)
		(fp_poly
			(pts
				(xy -3.504184 -2.09169) (xy -2.921 -1.800098) (xy -3.504184 -1.508506)
			)
			(stroke
				(width 0)
				(type default)
			)
			(fill yes)
			(layer "F.SilkS")
		)
		(fp_line
			(start 0.1778 -3.2385)
			(end 0.1778 -2.8575)
			(stroke
				(width 0.1)
				(type default)
			)
			(layer "F.Fab")
		)
		(fp_line
			(start -1.8034 -2.8702)
			(end -1.8034 -3.6322)
			(stroke
				(width 0.1)
				(type default)
			)
			(layer "F.Fab")
		)
		(fp_line
			(start 2.500122 -2.500122)
			(end 2.500122 2.500122)
			(stroke
				(width 0.1)
				(type default)
			)
			(layer "F.Fab")
		)
		(fp_line
			(start -2.500122 -2.500122)
			(end 2.500122 -2.500122)
			(stroke
				(width 0.1)
				(type default)
			)
			(layer "F.Fab")
		)
		(fp_line
			(start 2.8702 -1.778)
			(end 3.6322 -1.778)
			(stroke
				(width 0.1)
				(type default)
			)
			(layer "F.Fab")
		)
		(fp_line
			(start -3.2639 -0.1778)
			(end -2.8829 -0.1778)
			(stroke
				(width 0.1)
				(type default)
			)
			(layer "F.Fab")
		)
		(fp_line
			(start 2.8829 0.2032)
			(end 3.2639 0.2032)
			(stroke
				(width 0.1)
				(type default)
			)
			(layer "F.Fab")
		)
		(fp_line
			(start -3.6576 1.8034)
			(end -2.8956 1.8034)
			(stroke
				(width 0.1)
				(type default)
			)
			(layer "F.Fab")
		)
		(fp_line
			(start 2.500122 2.500122)
			(end -2.500122 2.500122)
			(stroke
				(width 0.1)
				(type default)
			)
			(layer "F.Fab")
		)
		(fp_line
			(start -2.500122 2.500122)
			(end -2.500122 -2.500122)
			(stroke
				(width 0.1)
				(type default)
			)
			(layer "F.Fab")
		)
		(fp_line
			(start -0.2032 2.8829)
			(end -0.2032 3.2639)
			(stroke
				(width 0.1)
				(type default)
			)
			(layer "F.Fab")
		)
		(fp_line
			(start 1.778 3.6322)
			(end 1.778 2.8702)
			(stroke
				(width 0.1)
				(type default)
			)
			(layer "F.Fab")
		)
		(fp_poly
			(pts
				(xy -2.921 -1.800098) (xy -3.504184 -1.508506) (xy -3.504184 -2.09169)
			)
			(stroke
				(width 0)
				(type default)
			)
			(fill yes)
			(layer "F.Fab")
		)
		(fp_text user "40"
			(at -2.684272 -3.844036 0)
			(unlocked yes)
			(layer "F.SilkS")
			(effects
				(font
					(size 0.635 0.4064)
					(thickness 0.1524)
				)
				(justify left)
			)
		)
		(fp_text user "31"
			(at 2.39268 -3.686556 0)
			(unlocked yes)
			(layer "F.SilkS")
			(effects
				(font
					(size 0.635 0.4064)
					(thickness 0.1524)
				)
				(justify left)
			)
		)
		(fp_text user "30"
			(at 3.363468 -1.184656 0)
			(unlocked yes)
			(layer "F.SilkS")
			(effects
				(font
					(size 0.635 0.4064)
					(thickness 0.1524)
				)
				(justify left)
			)
		)
		(fp_text user "21"
			(at 5.57276 2.102104 0)
			(unlocked yes)
			(layer "F.SilkS")
			(effects
				(font
					(size 0.635 0.4064)
					(thickness 0.1524)
				)
				(justify left)
			)
		)
		(fp_text user "10"
			(at -3.504692 2.1336 0)
			(unlocked yes)
			(layer "F.SilkS")
			(effects
				(font
					(size 0.635 0.4064)
					(thickness 0.1524)
				)
				(justify left)
			)
		)
		(fp_text user "20"
			(at 2.35712 2.881884 0)
			(unlocked yes)
			(layer "F.SilkS")
			(effects
				(font
					(size 0.635 0.4064)
					(thickness 0.1524)
				)
				(justify left)
			)
		)
		(fp_text user "11"
			(at -2.143252 2.955544 0)
			(unlocked yes)
			(layer "F.SilkS")
			(effects
				(font
					(size 0.635 0.4064)
					(thickness 0.1524)
				)
				(justify left)
			)
		)
		(fp_text user "31"
			(at 1.8542 -3.172968 90)
			(unlocked yes)
			(layer "F.Fab")
			(effects
				(font
					(size 0.635 0.4064)
					(thickness 0.1524)
				)
				(justify left)
			)
		)
		(fp_text user "40"
			(at -3.2004 -3.096768 90)
			(unlocked yes)
			(layer "F.Fab")
			(effects
				(font
					(size 0.635 0.4064)
					(thickness 0.1524)
				)
				(justify left)
			)
		)
		(fp_text user "30"
			(at 3.205988 -2.49682 0)
			(unlocked yes)
			(layer "F.Fab")
			(effects
				(font
					(size 0.635 0.4064)
					(thickness 0.1524)
				)
				(justify left)
			)
		)
		(fp_text user "21"
			(at 3.274568 1.8796 0)
			(unlocked yes)
			(layer "F.Fab")
			(effects
				(font
					(size 0.635 0.4064)
					(thickness 0.1524)
				)
				(justify left)
			)
		)
		(fp_text user "10"
			(at -3.253232 2.1336 0)
			(unlocked yes)
			(layer "F.Fab")
			(effects
				(font
					(size 0.635 0.4064)
					(thickness 0.1524)
				)
				(justify left)
			)
		)
		(fp_text user "20"
			(at 2.0828 3.253232 90)
			(unlocked yes)
			(layer "F.Fab")
			(effects
				(font
					(size 0.635 0.4064)
					(thickness 0.1524)
				)
				(justify left)
			)
		)
		(fp_text user "11"
			(at -2.8702 3.278632 90)
			(unlocked yes)
			(layer "F.Fab")
			(effects
				(font
					(size 0.635 0.4064)
					(thickness 0.1524)
				)
				(justify left)
			)
		)
		(pad "1" smd rect
			(at -2.400046 -1.800098)
			(size 0.1778 0.6096)
			(layers "F.Cu" "F.Mask" "F.Paste")
			(net "PVCCFA_EHV_CPU0_BPWM1")
		)
		(pad "2" smd rect
			(at -2.400046 -1.400048)
			(size 0.1778 0.6096)
			(layers "F.Cu" "F.Mask" "F.Paste")
			(net "NC_PVCCINFAON_CPU0_APWM7")
		)
		(pad "3" smd rect
			(at -2.400046 -0.999998)
			(size 0.1778 0.6096)
			(layers "F.Cu" "F.Mask" "F.Paste")
			(net "NC_PVCCINFAON_CPU0_APWM6")
		)
		(pad "4" smd rect
			(at -2.400046 -0.599948)
			(size 0.1778 0.6096)
			(layers "F.Cu" "F.Mask" "F.Paste")
			(net "NC_PVCCINFAON_CPU0_APWM5")
		)
		(pad "5" smd rect
			(at -2.400046 -0.199898)
			(size 0.1778 0.6096)
			(layers "F.Cu" "F.Mask" "F.Paste")
			(net "NC_PVCCINFAON_CPU0_APWM4")
		)
		(pad "6" smd rect
			(at -2.400046 0.199898)
			(size 0.1778 0.6096)
			(layers "F.Cu" "F.Mask" "F.Paste")
			(net "NC_PVCCINFAON_CPU0_APWM3")
		)
		(pad "7" smd rect
			(at -2.400046 0.599948)
			(size 0.1778 0.6096)
			(layers "F.Cu" "F.Mask" "F.Paste")
			(net "PVCCINFAON_CPU0_APWM2")
		)
		(pad "8" smd rect
			(at -2.400046 0.999998)
			(size 0.1778 0.6096)
			(layers "F.Cu" "F.Mask" "F.Paste")
			(net "PVCCINFAON_CPU0_APWM1")
		)
		(pad "9" smd rect
			(at -2.400046 1.400048)
			(size 0.1778 0.6096)
			(layers "F.Cu" "F.Mask" "F.Paste")
			(net "SMB_DIO_PVCCINFAON_CPU0")
		)
		(pad "10" smd rect
			(at -2.400046 1.800098)
			(size 0.1778 0.6096)
			(layers "F.Cu" "F.Mask" "F.Paste")
			(net "SMB_CLK_PVCCINFAON_CPU0")
		)
		(pad "11" smd rect
			(at -1.800098 2.400046 90)
			(size 0.1778 0.6096)
			(layers "F.Cu" "F.Mask" "F.Paste")
			(net "NC_PVCCINFAON_CPU0_SMB_ALERT")
		)
		(pad "12" smd rect
			(at -1.400048 2.400046 90)
			(size 0.1778 0.6096)
			(layers "F.Cu" "F.Mask" "F.Paste")
			(net "PWRGD_PVCCINFAON_CPU0_R")
		)
		(pad "13" smd rect
			(at -0.999998 2.400046 90)
			(size 0.1778 0.6096)
			(layers "F.Cu" "F.Mask" "F.Paste")
			(net "PVCCINFAON_CPU0_EN_R")
		)
		(pad "14" smd rect
			(at -0.599948 2.400046 90)
			(size 0.1778 0.6096)
			(layers "F.Cu" "F.Mask" "F.Paste")
			(net "IRQ_PVCCFA_CPU0_VRHOT_N")
		)
		(pad "15" smd rect
			(at -0.199898 2.400046 90)
			(size 0.1778 0.6096)
			(layers "F.Cu" "F.Mask" "F.Paste")
			(net "PVCCINFAON_CPU0_PIN_ALERT")
		)
		(pad "16" smd rect
			(at 0.199898 2.400046 90)
			(size 0.1778 0.6096)
			(layers "F.Cu" "F.Mask" "F.Paste")
			(net "PWRGD_PVCCFA_EHV_CPU0_R")
		)
		(pad "17" smd rect
			(at 0.599948 2.400046 90)
			(size 0.1778 0.6096)
			(layers "F.Cu" "F.Mask" "F.Paste")
			(net "SVID_CLK_PVCCINFAON_CPU0_R")
		)
		(pad "18" smd rect
			(at 0.999998 2.400046 90)
			(size 0.1778 0.6096)
			(layers "F.Cu" "F.Mask" "F.Paste")
			(net "SVID_DIO_PVCCINFAON_CPU0_R")
		)
		(pad "19" smd rect
			(at 1.400048 2.400046 90)
			(size 0.1778 0.6096)
			(layers "F.Cu" "F.Mask" "F.Paste")
			(net "SVID_ALERT_PVCCINFAON_CPU0_R")
		)
		(pad "20" smd rect
			(at 1.800098 2.400046 90)
			(size 0.1778 0.6096)
			(layers "F.Cu" "F.Mask" "F.Paste")
			(net "PVCCFA_EHV_CPU0_EN_R")
		)
		(pad "21" smd rect
			(at 2.400046 1.800098)
			(size 0.1778 0.6096)
			(layers "F.Cu" "F.Mask" "F.Paste")
			(net "SH_PVCCINFAON_CPU0_R")
		)
		(pad "22" smd rect
			(at 2.400046 1.400048)
			(size 0.1778 0.6096)
			(layers "F.Cu" "F.Mask" "F.Paste")
			(net "VSENSE_PVCCINFAON_CPU0_DN")
		)
		(pad "23" smd rect
			(at 2.400046 0.999998)
			(size 0.1778 0.6096)
			(layers "F.Cu" "F.Mask" "F.Paste")
			(net "PVCCINFAON_CPU0_ACSP1")
		)
		(pad "24" smd rect
			(at 2.400046 0.599948)
			(size 0.1778 0.6096)
			(layers "F.Cu" "F.Mask" "F.Paste")
			(net "PVCCINFAON_CPU0_ACSP2")
		)
		(pad "25" smd rect
			(at 2.400046 0.199898)
			(size 0.1778 0.6096)
			(layers "F.Cu" "F.Mask" "F.Paste")
			(net "NC_PVCCINFAON_CPU0_ACSP3")
		)
		(pad "26" smd rect
			(at 2.400046 -0.199898)
			(size 0.1778 0.6096)
			(layers "F.Cu" "F.Mask" "F.Paste")
			(net "NC_PVCCINFAON_CPU0_ACSP4")
		)
		(pad "27" smd rect
			(at 2.400046 -0.599948)
			(size 0.1778 0.6096)
			(layers "F.Cu" "F.Mask" "F.Paste")
			(net "NC_PVCCINFAON_CPU0_ACSP5")
		)
		(pad "28" smd rect
			(at 2.400046 -0.999998)
			(size 0.1778 0.6096)
			(layers "F.Cu" "F.Mask" "F.Paste")
			(net "NC_PVCCINFAON_CPU0_ACSP6")
		)
		(pad "29" smd rect
			(at 2.400046 -1.400048)
			(size 0.1778 0.6096)
			(layers "F.Cu" "F.Mask" "F.Paste")
			(net "NC_PVCCINFAON_CPU0_ACSP7")
		)
		(pad "30" smd rect
			(at 2.400046 -1.800098)
			(size 0.1778 0.6096)
			(layers "F.Cu" "F.Mask" "F.Paste")
			(net "PVCCFA_EHV_CPU0_BCSP1")
		)
		(pad "31" smd rect
			(at 1.800098 -2.400046 90)
			(size 0.1778 0.6096)
			(layers "F.Cu" "F.Mask" "F.Paste")
			(net "VSENSE_PVCCFA_EHV_CPU0_DN")
		)
		(pad "32" smd rect
			(at 1.400048 -2.400046 90)
			(size 0.1778 0.6096)
			(layers "F.Cu" "F.Mask" "F.Paste")
			(net "SH_PVCCFA_EHV_CPU0_R")
		)
		(pad "33" smd rect
			(at 0.999998 -2.400046 90)
			(size 0.1778 0.6096)
			(layers "F.Cu" "F.Mask" "F.Paste")
			(net "PVCCINFAON_CPU0_VR_FAULT")
		)
		(pad "34" smd rect
			(at 0.599948 -2.400046 90)
			(size 0.1778 0.6096)
			(layers "F.Cu" "F.Mask" "F.Paste")
			(net "PVCCINFAON_CPU0_ADDR")
		)
		(pad "35" smd rect
			(at 0.199898 -2.400046 90)
			(size 0.1778 0.6096)
			(layers "F.Cu" "F.Mask" "F.Paste")
			(net "PVCCINFAON_CPU0_ATSEN")
		)
		(pad "36" smd rect
			(at -0.199898 -2.400046 90)
			(size 0.1778 0.6096)
			(layers "F.Cu" "F.Mask" "F.Paste")
			(net "PVCCFA_EHV_CPU0_BTSEN")
		)
		(pad "37" smd rect
			(at -0.599948 -2.400046 90)
			(size 0.1778 0.6096)
			(layers "F.Cu" "F.Mask" "F.Paste")
			(net "PVCCINFAON_CPU0_CSPIN")
		)
		(pad "38" smd rect
			(at -0.999998 -2.400046 90)
			(size 0.1778 0.6096)
			(layers "F.Cu" "F.Mask" "F.Paste")
			(net "PVCCINFAON_CPU0_VIN_CSNIN")
		)
		(pad "39" smd rect
			(at -1.400048 -2.400046 90)
			(size 0.1778 0.6096)
			(layers "F.Cu" "F.Mask" "F.Paste")
			(net "PVCCINFAON_CPU0_VCC")
		)
		(pad "40" smd rect
			(at -1.800098 -2.400046 90)
			(size 0.1778 0.6096)
			(layers "F.Cu" "F.Mask" "F.Paste")
			(net "PVCCINFAON_CPU0_VREF")
		)
		(pad "TH" smd rect
			(at 0 0 90)
			(size 3.6576 3.6576)
			(layers "F.Cu" "F.Mask" "F.Paste")
			(net "GND")
		)
		(zone
			(layer "F.Cu")
			(hatch none 0.5)
			(connect_pads
				(clearance 0)
			)
			(min_thickness 0.25)
			(keepout
				(tracks not_allowed)
				(vias allowed)
				(pads allowed)
				(copperpour not_allowed)
				(footprints allowed)
			)
			(placement
				(enabled no)
				(sheetname "")
			)
			(fill
				(thermal_gap 0.5)
				(thermal_bridge_width 0.5)
				(island_removal_mode 0)
			)
			(polygon
				(pts
					(xy 423.673016 -134.38251) (xy 423.673016 -138.44651) (xy 427.737016 -138.44651) (xy 427.737016 -134.38251)
					(xy 423.850816 -134.38251) (xy 423.850816 -134.53491) (xy 427.584616 -134.53491) (xy 427.584616 -138.29411)
					(xy 423.825416 -138.29411) (xy 423.825416 -134.38251)
				)
			)
		)
	)
)
